# TIMECARD (Time Appliance Project (Time Card)) — schematic netlist excerpt (pin names and nets, part order shuffled) for the footprints in the layout excerpt that follows; sources: Cadence DE-HDL packaged netlist, KiCad conversion of R4006-B0001-02_R01.brd

R414  RESISTOR  4.7KOHM 1%  pkg SMC_0402R_H016  page 17 : \1\ = XP3R3V_FPGA ; \2\ = UNNAMED_6_LM75BDPTSSOP8_I81_A1
R94  RESISTOR  33OHM 1%  pkg SMC_0402R_H016  page 21 : \1\ = R_MAC_UART_TX_FPGA_RX ; \2\ = UART_MAC_TX_FPGA_RX

(kicad_pcb
	(version 20260206)
	(generator "pcbnew")
	(generator_version "10.0")
	(general
		(thickness 1.6)
		(legacy_teardrops no)
	)
	(paper "A4")
	(title_block
		(title "timecard-production-celestica-r4006 — R4006-B0001-02_R01.brd")
		(comment 1 "Time Appliance Project (Time Card) / footprints 12-13 of 1113")
	)
	(layers
		(0 "F.Cu" signal "TOP")
		(4 "In1.Cu" signal "L02_GND1")
		(6 "In2.Cu" signal "L03_SIG1")
		(8 "In3.Cu" signal "L04_GND2")
		(10 "In4.Cu" signal "L05_VCC1")
		(12 "In5.Cu" signal "L06_VCC2")
		(14 "In6.Cu" signal "L07_GND3")
		(16 "In7.Cu" signal "L08_SIG2")
		(18 "In8.Cu" signal "L09_GND4")
		(2 "B.Cu" signal "BOTTOM")
		(9 "F.Adhes" user "F.Adhesive")
		(11 "B.Adhes" user "B.Adhesive")
		(13 "F.Paste" user "Package Geometry/Pastemask Top")
		(15 "B.Paste" user "Package Geometry/Pastemask Bottom")
		(5 "F.SilkS" user "Ref Des/Silkscreen Top")
		(7 "B.SilkS" user "Ref Des/Silkscreen Bottom")
		(1 "F.Mask" user "Board Geometry/Soldermask Top")
		(3 "B.Mask" user "Board Geometry/Soldermask Bottom")
		(17 "Dwgs.User" user "User.Drawings")
		(19 "Cmts.User" user "User.Comments")
		(21 "Eco1.User" user "User.Eco1")
		(23 "Eco2.User" user "User.Eco2")
		(25 "Edge.Cuts" user "Board Geometry/Outline")
		(27 "Margin" user)
		(31 "F.CrtYd" user "Package Geometry/Place Bound Top")
		(29 "B.CrtYd" user "Package Geometry/Place Bound Bottom")
		(35 "F.Fab" user "Ref Des/Assembly Top")
		(33 "B.Fab" user "Ref Des/Assembly Bottom")
	)
	(footprint ""
		(layer "F.Cu")
		(at 162.56 -25.908 180)
		(property "Reference" "R414"
			(at -2.667 -0.80137 0)
			(unlocked yes)
			(layer "F.SilkS")
			(effects
				(font
					(size 0.7874 0.5842)
					(thickness 0.1524)
				)
			)
		)
		(property "Value" "VAL*"
			(at 0.02032 2.13233 180)
			(unlocked yes)
			(layer "F.Fab")
			(hide yes)
			(effects
				(font
					(size 0.7874 0.5842)
					(thickness 0.1524)
				)
			)
		)
		(property "Tolerance" "TOL*"
			(at 0.044704 3.05435 180)
			(unlocked yes)
			(layer "Cmts.User")
			(hide yes)
			(effects
				(font
					(size 0.7874 0.5842)
					(thickness 0.1524)
				)
			)
		)
		(property "User Part Number" "PARTNUM*"
			(at 0.02032 4.024884 180)
			(unlocked yes)
			(layer "Cmts.User")
			(hide yes)
			(effects
				(font
					(size 0.7874 0.5842)
					(thickness 0.1524)
				)
			)
		)
		(property "Device Type" "RESISTOR-G155-14701-01,4.7KOHMA"
			(at 0.008382 1.210564 180)
			(unlocked yes)
			(layer "F.Fab")
			(hide yes)
			(effects
				(font
					(size 0.7874 0.5842)
					(thickness 0.1524)
				)
			)
		)
		(duplicate_pad_numbers_are_jumpers no)
		(fp_line
			(start 1.143 0.5588)
			(end 1.143 -0.5588)
			(stroke
				(width 0.1)
				(type default)
			)
			(layer "F.SilkS")
		)
		(fp_line
			(start 1.143 -0.5588)
			(end -1.143 -0.5588)
			(stroke
				(width 0.1)
				(type default)
			)
			(layer "F.SilkS")
		)
		(fp_line
			(start -1.143 0.5588)
			(end 1.143 0.5588)
			(stroke
				(width 0.1)
				(type default)
			)
			(layer "F.SilkS")
		)
		(fp_line
			(start -1.143 -0.5588)
			(end -1.143 0.5588)
			(stroke
				(width 0.1)
				(type default)
			)
			(layer "F.SilkS")
		)
		(fp_rect
			(start 1.143 -0.5588)
			(end -1.143 0.5588)
			(stroke
				(width 0)
				(type default)
			)
			(fill no)
			(layer "F.CrtYd")
		)
		(fp_line
			(start 0.508 0.3048)
			(end 0.508 -0.3048)
			(stroke
				(width 0.1)
				(type default)
			)
			(layer "F.Fab")
		)
		(fp_line
			(start 0.508 -0.3048)
			(end -0.508 -0.3048)
			(stroke
				(width 0.1)
				(type default)
			)
			(layer "F.Fab")
		)
		(fp_line
			(start -0.508 0.3048)
			(end 0.508 0.3048)
			(stroke
				(width 0.1)
				(type default)
			)
			(layer "F.Fab")
		)
		(fp_line
			(start -0.508 -0.3048)
			(end -0.508 0.3048)
			(stroke
				(width 0.1)
				(type default)
			)
			(layer "F.Fab")
		)
		(pad "1" smd rect
			(at -0.5334 0 180)
			(size 0.7112 0.6096)
			(layers "F.Cu" "F.Mask" "F.Paste")
			(net "XP3R3V_FPGA")
		)
		(pad "2" smd rect
			(at 0.5334 0 180)
			(size 0.7112 0.6096)
			(layers "F.Cu" "F.Mask" "F.Paste")
			(net "UNNAMED_6_LM75BDPTSSOP8_I81_A1")
		)
		(zone
			(layer "F.Cu")
			(hatch none 0.5)
			(connect_pads
				(clearance 0)
			)
			(min_thickness 0.25)
			(keepout
				(tracks allowed)
				(vias not_allowed)
				(pads allowed)
				(copperpour not_allowed)
				(footprints allowed)
			)
			(placement
				(enabled no)
				(sheetname "")
			)
			(fill
				(thermal_gap 0.5)
				(thermal_bridge_width 0.5)
				(island_removal_mode 0)
			)
			(polygon
				(pts
					(xy 162.4838 -25.6032) (xy 162.6362 -25.6032) (xy 162.6362 -26.2128) (xy 162.4838 -26.2128)
				)
			)
		)
		(zone
			(layer "F.Cu")
			(hatch none 0.5)
			(connect_pads
				(clearance 0)
			)
			(min_thickness 0.25)
			(keepout
				(tracks not_allowed)
				(vias allowed)
				(pads allowed)
				(copperpour not_allowed)
				(footprints allowed)
			)
			(placement
				(enabled no)
				(sheetname "")
			)
			(fill
				(thermal_gap 0.5)
				(thermal_bridge_width 0.5)
				(island_removal_mode 0)
			)
			(polygon
				(pts
					(xy 162.4838 -25.6032) (xy 162.6362 -25.6032) (xy 162.6362 -26.2128) (xy 162.4838 -26.2128)
				)
			)
		)
	)
	(footprint ""
		(layer "F.Cu")
		(at 124.587 -50.165 180)
		(property "Reference" "R94"
			(at -0.127 -2.45237 0)
			(unlocked yes)
			(layer "F.SilkS")
			(effects
				(font
					(size 0.7874 0.5842)
					(thickness 0.1524)
				)
			)
		)
		(property "Value" "VAL*"
			(at 0.02032 2.13233 180)
			(unlocked yes)
			(layer "F.Fab")
			(hide yes)
			(effects
				(font
					(size 0.7874 0.5842)
					(thickness 0.1524)
				)
			)
		)
		(property "Device Type" "RESISTOR-G155-133R0-01,33OHM,1%"
			(at 0.008382 1.210564 180)
			(unlocked yes)
			(layer "F.Fab")
			(hide yes)
			(effects
				(font
					(size 0.7874 0.5842)
					(thickness 0.1524)
				)
			)
		)
		(property "User Part Number" "PARTNUM*"
			(at 0.02032 4.024884 180)
			(unlocked yes)
			(layer "Cmts.User")
			(hide yes)
			(effects
				(font
					(size 0.7874 0.5842)
					(thickness 0.1524)
				)
			)
		)
		(property "Tolerance" "TOL*"
			(at 0.044704 3.05435 180)
			(unlocked yes)
			(layer "Cmts.User")
			(hide yes)
			(effects
				(font
					(size 0.7874 0.5842)
					(thickness 0.1524)
				)
			)
		)
		(duplicate_pad_numbers_are_jumpers no)
		(fp_line
			(start 1.143 0.5588)
			(end 1.143 -0.5588)
			(stroke
				(width 0.1)
				(type default)
			)
			(layer "F.SilkS")
		)
		(fp_line
			(start 1.143 -0.5588)
			(end -1.143 -0.5588)
			(stroke
				(width 0.1)
				(type default)
			)
			(layer "F.SilkS")
		)
		(fp_line
			(start -1.143 0.5588)
			(end 1.143 0.5588)
			(stroke
				(width 0.1)
				(type default)
			)
			(layer "F.SilkS")
		)
		(fp_line
			(start -1.143 -0.5588)
			(end -1.143 0.5588)
			(stroke
				(width 0.1)
				(type default)
			)
			(layer "F.SilkS")
		)
		(fp_rect
			(start 1.143 -0.5588)
			(end -1.143 0.5588)
			(stroke
				(width 0)
				(type default)
			)
			(fill no)
			(layer "F.CrtYd")
		)
		(fp_line
			(start 0.508 0.3048)
			(end 0.508 -0.3048)
			(stroke
				(width 0.1)
				(type default)
			)
			(layer "F.Fab")
		)
		(fp_line
			(start 0.508 -0.3048)
			(end -0.508 -0.3048)
			(stroke
				(width 0.1)
				(type default)
			)
			(layer "F.Fab")
		)
		(fp_line
			(start -0.508 0.3048)
			(end 0.508 0.3048)
			(stroke
				(width 0.1)
				(type default)
			)
			(layer "F.Fab")
		)
		(fp_line
			(start -0.508 -0.3048)
			(end -0.508 0.3048)
			(stroke
				(width 0.1)
				(type default)
			)
			(layer "F.Fab")
		)
		(pad "1" smd rect
			(at -0.5334 0 180)
			(size 0.7112 0.6096)
			(layers "F.Cu" "F.Mask" "F.Paste")
			(net "R_MAC_UART_TX_FPGA_RX")
		)
		(pad "2" smd rect
			(at 0.5334 0 180)
			(size 0.7112 0.6096)
			(layers "F.Cu" "F.Mask" "F.Paste")
			(net "UART_MAC_TX_FPGA_RX")
		)
		(zone
			(layer "F.Cu")
			(hatch none 0.5)
			(connect_pads
				(clearance 0)
			)
			(min_thickness 0.25)
			(keepout
				(tracks allowed)
				(vias not_allowed)
				(pads allowed)
				(copperpour not_allowed)
				(footprints allowed)
			)
			(placement
				(enabled no)
				(sheetname "")
			)
			(fill
				(thermal_gap 0.5)
				(thermal_bridge_width 0.5)
				(island_removal_mode 0)
			)
			(polygon
				(pts
					(xy 124.5108 -49.8602) (xy 124.6632 -49.8602) (xy 124.6632 -50.4698) (xy 124.5108 -50.4698)
				)
			)
		)
	)
)
